(kicad_pcb
	(version 20260206)
	(generator "pcbnew")
	(generator_version "10.0")
	(general
		(thickness 1.6)
		(legacy_teardrops no)
	)
	(paper "A4")
	(title_block
		(title "01162023_DA0F0TEBIF0_F0T_Expander_BD_F_brd_V02_OCP.brd")
		(comment 1 "Grand Teton / footprints 8151-8160 of 9728")
	)
	(layers
		(0 "F.Cu" signal "TOP")
		(4 "In1.Cu" signal "GND")
		(6 "In2.Cu" signal "VCC")
		(8 "In3.Cu" signal "VCC1")
		(10 "In4.Cu" signal "GND1")
		(12 "In5.Cu" signal "IN1")
		(14 "In6.Cu" signal "GND2")
		(16 "In7.Cu" signal "IN2")
		(18 "In8.Cu" signal "GND3")
		(20 "In9.Cu" signal "IN3")
		(22 "In10.Cu" signal "GND4")
		(24 "In11.Cu" signal "IN4")
		(26 "In12.Cu" signal "GND5")
		(28 "In13.Cu" signal "IN5")
		(30 "In14.Cu" signal "GND6")
		(32 "In15.Cu" signal "IN6")
		(34 "In16.Cu" signal "GND7")
		(2 "B.Cu" signal "BOTTOM")
		(9 "F.Adhes" user "F.Adhesive")
		(11 "B.Adhes" user "B.Adhesive")
		(13 "F.Paste" user "Package Geometry/Pastemask Top")
		(15 "B.Paste" user "Package Geometry/Pastemask Bottom")
		(5 "F.SilkS" user "Ref Des/Silkscreen Top")
		(7 "B.SilkS" user "Ref Des/Silkscreen Bottom")
		(1 "F.Mask" user "Board Geometry/Soldermask Top")
		(3 "B.Mask" user "Board Geometry/Soldermask Bottom")
		(17 "Dwgs.User" user "User.Drawings")
		(19 "Cmts.User" user "User.Comments")
		(21 "Eco1.User" user "User.Eco1")
		(23 "Eco2.User" user "User.Eco2")
		(25 "Edge.Cuts" user "Board Geometry/Outline")
		(27 "Margin" user)
		(31 "F.CrtYd" user "Package Geometry/Place Bound Top")
		(29 "B.CrtYd" user "Package Geometry/Place Bound Bottom")
		(35 "F.Fab" user "Ref Des/Assembly Top")
		(33 "B.Fab" user "Ref Des/Assembly Bottom")
	)
	(footprint ""
		(layer "B.Cu")
		(at 349.264986 -255.86055 180)
		(property "Reference" "PC124"
			(at 0 0 0)
			(layer "B.SilkS")
			(hide yes)
			(effects
				(font
					(size 1.27 1.27)
				)
				(justify mirror)
			)
		)
		(property "Value" ""
			(at 0 0 0)
			(layer "B.Fab")
			(effects
				(font
					(size 1.27 1.27)
				)
				(justify mirror)
			)
		)
		(duplicate_pad_numbers_are_jumpers no)
		(fp_line
			(start 0.7874 0.4064)
			(end 0.7874 -0.4064)
			(stroke
				(width 0.1524)
				(type default)
			)
			(layer "B.SilkS")
		)
		(fp_line
			(start 0.7874 -0.4064)
			(end -0.7874 -0.4064)
			(stroke
				(width 0.1524)
				(type default)
			)
			(layer "B.SilkS")
		)
		(fp_line
			(start -0.7874 0.4064)
			(end 0.7874 0.4064)
			(stroke
				(width 0.1524)
				(type default)
			)
			(layer "B.SilkS")
		)
		(fp_line
			(start -0.7874 -0.4064)
			(end -0.7874 0.4064)
			(stroke
				(width 0.1524)
				(type default)
			)
			(layer "B.SilkS")
		)
		(fp_line
			(start 0.67945 0.3048)
			(end 0.67945 -0.305054)
			(stroke
				(width 0.1)
				(type default)
			)
			(layer "B.Fab")
		)
		(fp_line
			(start 0.67945 -0.305054)
			(end 0.12065 -0.305054)
			(stroke
				(width 0.1)
				(type default)
			)
			(layer "B.Fab")
		)
		(fp_line
			(start 0.12065 0.3048)
			(end 0.67945 0.3048)
			(stroke
				(width 0.1)
				(type default)
			)
			(layer "B.Fab")
		)
		(fp_line
			(start 0.12065 0.2794)
			(end 0.12065 0.3048)
			(stroke
				(width 0.1)
				(type default)
			)
			(layer "B.Fab")
		)
		(fp_line
			(start 0.12065 -0.2794)
			(end -0.12065 -0.2794)
			(stroke
				(width 0.1)
				(type default)
			)
			(layer "B.Fab")
		)
		(fp_line
			(start 0.12065 -0.305054)
			(end 0.12065 -0.2794)
			(stroke
				(width 0.1)
				(type default)
			)
			(layer "B.Fab")
		)
		(fp_line
			(start -0.120396 0.3048)
			(end -0.120396 0.2794)
			(stroke
				(width 0.1)
				(type default)
			)
			(layer "B.Fab")
		)
		(fp_line
			(start -0.120396 0.2794)
			(end 0.12065 0.2794)
			(stroke
				(width 0.1)
				(type default)
			)
			(layer "B.Fab")
		)
		(fp_line
			(start -0.12065 -0.2794)
			(end -0.12065 -0.3048)
			(stroke
				(width 0.1)
				(type default)
			)
			(layer "B.Fab")
		)
		(fp_line
			(start -0.12065 -0.3048)
			(end -0.67945 -0.3048)
			(stroke
				(width 0.1)
				(type default)
			)
			(layer "B.Fab")
		)
		(fp_line
			(start -0.67945 0.3048)
			(end -0.120396 0.3048)
			(stroke
				(width 0.1)
				(type default)
			)
			(layer "B.Fab")
		)
		(fp_line
			(start -0.67945 -0.3048)
			(end -0.67945 0.3048)
			(stroke
				(width 0.1)
				(type default)
			)
			(layer "B.Fab")
		)
		(pad "1" smd circle
			(at 0.40005 0)
			(size 0 0)
			(layers "B.Cu" "B.Mask" "B.Paste")
			(net "P0V8_PEX2_VDD")
		)
		(pad "2" smd circle
			(at -0.40005 0)
			(size 0 0)
			(layers "B.Cu" "B.Mask" "B.Paste")
			(net "GND")
		)
	)
	(footprint ""
		(layer "B.Cu")
		(at 280.924762 -297.79976 -90)
		(property "Reference" "C1633"
			(at 0 0 90)
			(layer "B.SilkS")
			(hide yes)
			(effects
				(font
					(size 1.27 1.27)
				)
				(justify mirror)
			)
		)
		(property "Value" ""
			(at 0 0 90)
			(layer "B.Fab")
			(effects
				(font
					(size 1.27 1.27)
				)
				(justify mirror)
			)
		)
		(duplicate_pad_numbers_are_jumpers no)
		(fp_line
			(start -0.299974 0.150114)
			(end 0.299974 0.150114)
			(stroke
				(width 0.1)
				(type default)
			)
			(layer "B.Fab")
		)
		(fp_line
			(start 0.299974 0.150114)
			(end 0.299974 -0.150114)
			(stroke
				(width 0.1)
				(type default)
			)
			(layer "B.Fab")
		)
		(fp_line
			(start -0.299974 -0.150114)
			(end -0.299974 0.150114)
			(stroke
				(width 0.1)
				(type default)
			)
			(layer "B.Fab")
		)
		(fp_line
			(start 0.299974 -0.150114)
			(end -0.299974 -0.150114)
			(stroke
				(width 0.1)
				(type default)
			)
			(layer "B.Fab")
		)
		(pad "1" smd rect
			(at 0.2667 0 90)
			(size 0.3048 0.381)
			(layers "B.Cu" "B.Mask" "B.Paste")
			(net "P0V8_PEX2")
		)
		(pad "2" smd rect
			(at -0.2667 0 90)
			(size 0.3048 0.381)
			(layers "B.Cu" "B.Mask" "B.Paste")
			(net "GND")
		)
	)
	(footprint ""
		(layer "B.Cu")
		(at 424.016932 -295.42486)
		(property "Reference" "C3423"
			(at 0 0 0)
			(layer "B.SilkS")
			(hide yes)
			(effects
				(font
					(size 1.27 1.27)
				)
				(justify mirror)
			)
		)
		(property "Value" ""
			(at 0 0 0)
			(layer "B.Fab")
			(effects
				(font
					(size 1.27 1.27)
				)
				(justify mirror)
			)
		)
		(duplicate_pad_numbers_are_jumpers no)
		(fp_line
			(start -1.2954 -0.5842)
			(end -1.2954 0.5842)
			(stroke
				(width 0.1524)
				(type default)
			)
			(layer "B.SilkS")
		)
		(fp_line
			(start -1.2954 0.5842)
			(end 1.2954 0.5842)
			(stroke
				(width 0.1524)
				(type default)
			)
			(layer "B.SilkS")
		)
		(fp_line
			(start 1.2954 -0.5842)
			(end -1.2954 -0.5842)
			(stroke
				(width 0.1524)
				(type default)
			)
			(layer "B.SilkS")
		)
		(fp_line
			(start 1.2954 0.5842)
			(end 1.2954 -0.5842)
			(stroke
				(width 0.1524)
				(type default)
			)
			(layer "B.SilkS")
		)
		(fp_line
			(start -1.1938 -0.4064)
			(end -1.1938 0.4064)
			(stroke
				(width 0.1)
				(type default)
			)
			(layer "B.Fab")
		)
		(fp_line
			(start -1.1938 0.4064)
			(end -0.8636 0.4064)
			(stroke
				(width 0.1)
				(type default)
			)
			(layer "B.Fab")
		)
		(fp_line
			(start -0.8636 -0.4572)
			(end -0.8636 -0.4064)
			(stroke
				(width 0.1)
				(type default)
			)
			(layer "B.Fab")
		)
		(fp_line
			(start -0.8636 -0.4064)
			(end -1.1938 -0.4064)
			(stroke
				(width 0.1)
				(type default)
			)
			(layer "B.Fab")
		)
		(fp_line
			(start -0.8636 0.4064)
			(end -0.8636 0.4572)
			(stroke
				(width 0.1)
				(type default)
			)
			(layer "B.Fab")
		)
		(fp_line
			(start -0.8636 0.4572)
			(end 0.8636 0.4572)
			(stroke
				(width 0.1)
				(type default)
			)
			(layer "B.Fab")
		)
		(fp_line
			(start 0.8636 -0.4572)
			(end -0.8636 -0.4572)
			(stroke
				(width 0.1)
				(type default)
			)
			(layer "B.Fab")
		)
		(fp_line
			(start 0.8636 -0.4064)
			(end 0.8636 -0.4572)
			(stroke
				(width 0.1)
				(type default)
			)
			(layer "B.Fab")
		)
		(fp_line
			(start 0.8636 0.4064)
			(end 1.1938 0.4064)
			(stroke
				(width 0.1)
				(type default)
			)
			(layer "B.Fab")
		)
		(fp_line
			(start 0.8636 0.4572)
			(end 0.8636 0.4064)
			(stroke
				(width 0.1)
				(type default)
			)
			(layer "B.Fab")
		)
		(fp_line
			(start 1.1938 -0.4064)
			(end 0.8636 -0.4064)
			(stroke
				(width 0.1)
				(type default)
			)
			(layer "B.Fab")
		)
		(fp_line
			(start 1.1938 0.4064)
			(end 1.1938 -0.4064)
			(stroke
				(width 0.1)
				(type default)
			)
			(layer "B.Fab")
		)
		(pad "1" smd rect
			(at 0.7366 0 270)
			(size 0.7112 0.8128)
			(layers "B.Cu" "B.Mask" "B.Paste")
			(net "P1V25_PEX3")
		)
		(pad "2" smd rect
			(at -0.7366 0 270)
			(size 0.7112 0.8128)
			(layers "B.Cu" "B.Mask" "B.Paste")
			(net "GND")
		)
	)
	(footprint ""
		(layer "B.Cu")
		(at 409.849828 -299.699934 -90)
		(property "Reference" "C1977"
			(at 0 0 90)
			(layer "B.SilkS")
			(hide yes)
			(effects
				(font
					(size 1.27 1.27)
				)
				(justify mirror)
			)
		)
		(property "Value" ""
			(at 0 0 90)
			(layer "B.Fab")
			(effects
				(font
					(size 1.27 1.27)
				)
				(justify mirror)
			)
		)
		(duplicate_pad_numbers_are_jumpers no)
		(fp_line
			(start -0.299974 0.150114)
			(end 0.299974 0.150114)
			(stroke
				(width 0.1)
				(type default)
			)
			(layer "B.Fab")
		)
		(fp_line
			(start 0.299974 0.150114)
			(end 0.299974 -0.150114)
			(stroke
				(width 0.1)
				(type default)
			)
			(layer "B.Fab")
		)
		(fp_line
			(start -0.299974 -0.150114)
			(end -0.299974 0.150114)
			(stroke
				(width 0.1)
				(type default)
			)
			(layer "B.Fab")
		)
		(fp_line
			(start 0.299974 -0.150114)
			(end -0.299974 -0.150114)
			(stroke
				(width 0.1)
				(type default)
			)
			(layer "B.Fab")
		)
		(pad "1" smd rect
			(at 0.2667 0 90)
			(size 0.3048 0.381)
			(layers "B.Cu" "B.Mask" "B.Paste")
			(net "P0V8_SERDES_VDDA_PEX3")
		)
		(pad "2" smd rect
			(at -0.2667 0 90)
			(size 0.3048 0.381)
			(layers "B.Cu" "B.Mask" "B.Paste")
			(net "GND")
		)
	)
	(footprint ""
		(layer "B.Cu")
		(at 118.456964 -317.706756)
		(property "Reference" "C4267"
			(at 0 0 0)
			(layer "B.SilkS")
			(hide yes)
			(effects
				(font
					(size 1.27 1.27)
				)
				(justify mirror)
			)
		)
		(property "Value" ""
			(at 0 0 0)
			(layer "B.Fab")
			(effects
				(font
					(size 1.27 1.27)
				)
				(justify mirror)
			)
		)
		(duplicate_pad_numbers_are_jumpers no)
		(fp_line
			(start -0.299974 -0.150114)
			(end -0.299974 0.150114)
			(stroke
				(width 0.1)
				(type default)
			)
			(layer "B.Fab")
		)
		(fp_line
			(start -0.299974 0.150114)
			(end 0.299974 0.150114)
			(stroke
				(width 0.1)
				(type default)
			)
			(layer "B.Fab")
		)
		(fp_line
			(start 0.299974 -0.150114)
			(end -0.299974 -0.150114)
			(stroke
				(width 0.1)
				(type default)
			)
			(layer "B.Fab")
		)
		(fp_line
			(start 0.299974 0.150114)
			(end 0.299974 -0.150114)
			(stroke
				(width 0.1)
				(type default)
			)
			(layer "B.Fab")
		)
		(pad "1" smd rect
			(at 0.2667 0 180)
			(size 0.3048 0.381)
			(layers "B.Cu" "B.Mask" "B.Paste")
			(net "P0V8_SERDES_VDDA_PEX1")
		)
		(pad "2" smd rect
			(at -0.2667 0 180)
			(size 0.3048 0.381)
			(layers "B.Cu" "B.Mask" "B.Paste")
			(net "GND")
		)
	)
	(footprint ""
		(layer "B.Cu")
		(at 295.670224 -296.37482)
		(property "Reference" "C1617"
			(at 0 0 0)
			(layer "B.SilkS")
			(hide yes)
			(effects
				(font
					(size 1.27 1.27)
				)
				(justify mirror)
			)
		)
		(property "Value" ""
			(at 0 0 0)
			(layer "B.Fab")
			(effects
				(font
					(size 1.27 1.27)
				)
				(justify mirror)
			)
		)
		(duplicate_pad_numbers_are_jumpers no)
		(fp_line
			(start -0.299974 -0.150114)
			(end -0.299974 0.150114)
			(stroke
				(width 0.1)
				(type default)
			)
			(layer "B.Fab")
		)
		(fp_line
			(start -0.299974 0.150114)
			(end 0.299974 0.150114)
			(stroke
				(width 0.1)
				(type default)
			)
			(layer "B.Fab")
		)
		(fp_line
			(start 0.299974 -0.150114)
			(end -0.299974 -0.150114)
			(stroke
				(width 0.1)
				(type default)
			)
			(layer "B.Fab")
		)
		(fp_line
			(start 0.299974 0.150114)
			(end 0.299974 -0.150114)
			(stroke
				(width 0.1)
				(type default)
			)
			(layer "B.Fab")
		)
		(pad "1" smd rect
			(at 0.2667 0 180)
			(size 0.3048 0.381)
			(layers "B.Cu" "B.Mask" "B.Paste")
			(net "P0V8_PEX2")
		)
		(pad "2" smd rect
			(at -0.2667 0 180)
			(size 0.3048 0.381)
			(layers "B.Cu" "B.Mask" "B.Paste")
			(net "GND")
		)
	)
	(footprint ""
		(layer "B.Cu")
		(at 410.799788 -292.099746 90)
		(property "Reference" "C1978"
			(at 0 0 90)
			(layer "B.SilkS")
			(hide yes)
			(effects
				(font
					(size 1.27 1.27)
				)
				(justify mirror)
			)
		)
		(property "Value" ""
			(at 0 0 90)
			(layer "B.Fab")
			(effects
				(font
					(size 1.27 1.27)
				)
				(justify mirror)
			)
		)
		(duplicate_pad_numbers_are_jumpers no)
		(fp_line
			(start 0.299974 -0.150114)
			(end -0.299974 -0.150114)
			(stroke
				(width 0.1)
				(type default)
			)
			(layer "B.Fab")
		)
		(fp_line
			(start -0.299974 -0.150114)
			(end -0.299974 0.150114)
			(stroke
				(width 0.1)
				(type default)
			)
			(layer "B.Fab")
		)
		(fp_line
			(start 0.299974 0.150114)
			(end 0.299974 -0.150114)
			(stroke
				(width 0.1)
				(type default)
			)
			(layer "B.Fab")
		)
		(fp_line
			(start -0.299974 0.150114)
			(end 0.299974 0.150114)
			(stroke
				(width 0.1)
				(type default)
			)
			(layer "B.Fab")
		)
		(pad "1" smd rect
			(at 0.2667 0 270)
			(size 0.3048 0.381)
			(layers "B.Cu" "B.Mask" "B.Paste")
			(net "P0V8_SERDES_VDDA_PEX3")
		)
		(pad "2" smd rect
			(at -0.2667 0 270)
			(size 0.3048 0.381)
			(layers "B.Cu" "B.Mask" "B.Paste")
			(net "GND")
		)
	)
	(footprint ""
		(layer "B.Cu")
		(at 288.049716 -288.299906 90)
		(property "Reference" "C3290"
			(at 0 0 90)
			(layer "B.SilkS")
			(hide yes)
			(effects
				(font
					(size 1.27 1.27)
				)
				(justify mirror)
			)
		)
		(property "Value" ""
			(at 0 0 90)
			(layer "B.Fab")
			(effects
				(font
					(size 1.27 1.27)
				)
				(justify mirror)
			)
		)
		(duplicate_pad_numbers_are_jumpers no)
		(fp_line
			(start 0.299974 -0.150114)
			(end -0.299974 -0.150114)
			(stroke
				(width 0.1)
				(type default)
			)
			(layer "B.Fab")
		)
		(fp_line
			(start -0.299974 -0.150114)
			(end -0.299974 0.150114)
			(stroke
				(width 0.1)
				(type default)
			)
			(layer "B.Fab")
		)
		(fp_line
			(start 0.299974 0.150114)
			(end 0.299974 -0.150114)
			(stroke
				(width 0.1)
				(type default)
			)
			(layer "B.Fab")
		)
		(fp_line
			(start -0.299974 0.150114)
			(end 0.299974 0.150114)
			(stroke
				(width 0.1)
				(type default)
			)
			(layer "B.Fab")
		)
		(pad "1" smd rect
			(at 0.2667 0 270)
			(size 0.3048 0.381)
			(layers "B.Cu" "B.Mask" "B.Paste")
			(net "P1V25_PEX2")
		)
		(pad "2" smd rect
			(at -0.2667 0 270)
			(size 0.3048 0.381)
			(layers "B.Cu" "B.Mask" "B.Paste")
			(net "GND")
		)
	)
	(footprint ""
		(layer "B.Cu")
		(at 134.300214 -206.793846 -90)
		(property "Reference" "C2585"
			(at 0 0 90)
			(layer "B.SilkS")
			(hide yes)
			(effects
				(font
					(size 1.27 1.27)
				)
				(justify mirror)
			)
		)
		(property "Value" ""
			(at 0 0 90)
			(layer "B.Fab")
			(effects
				(font
					(size 1.27 1.27)
				)
				(justify mirror)
			)
		)
		(duplicate_pad_numbers_are_jumpers no)
		(fp_line
			(start -0.7874 0.4064)
			(end 0.7874 0.4064)
			(stroke
				(width 0.1524)
				(type default)
			)
			(layer "B.SilkS")
		)
		(fp_line
			(start 0.7874 0.4064)
			(end 0.7874 -0.4064)
			(stroke
				(width 0.1524)
				(type default)
			)
			(layer "B.SilkS")
		)
		(fp_line
			(start -0.7874 -0.4064)
			(end -0.7874 0.4064)
			(stroke
				(width 0.1524)
				(type default)
			)
			(layer "B.SilkS")
		)
		(fp_line
			(start 0.7874 -0.4064)
			(end -0.7874 -0.4064)
			(stroke
				(width 0.1524)
				(type default)
			)
			(layer "B.SilkS")
		)
		(fp_line
			(start -0.67945 0.3048)
			(end -0.120396 0.3048)
			(stroke
				(width 0.1)
				(type default)
			)
			(layer "B.Fab")
		)
		(fp_line
			(start -0.120396 0.3048)
			(end -0.120396 0.2794)
			(stroke
				(width 0.1)
				(type default)
			)
			(layer "B.Fab")
		)
		(fp_line
			(start 0.12065 0.3048)
			(end 0.67945 0.3048)
			(stroke
				(width 0.1)
				(type default)
			)
			(layer "B.Fab")
		)
		(fp_line
			(start 0.67945 0.3048)
			(end 0.67945 -0.305054)
			(stroke
				(width 0.1)
				(type default)
			)
			(layer "B.Fab")
		)
		(fp_line
			(start -0.120396 0.2794)
			(end 0.12065 0.2794)
			(stroke
				(width 0.1)
				(type default)
			)
			(layer "B.Fab")
		)
		(fp_line
			(start 0.12065 0.2794)
			(end 0.12065 0.3048)
			(stroke
				(width 0.1)
				(type default)
			)
			(layer "B.Fab")
		)
		(fp_line
			(start -0.12065 -0.2794)
			(end -0.12065 -0.3048)
			(stroke
				(width 0.1)
				(type default)
			)
			(layer "B.Fab")
		)
		(fp_line
			(start 0.12065 -0.2794)
			(end -0.12065 -0.2794)
			(stroke
				(width 0.1)
				(type default)
			)
			(layer "B.Fab")
		)
		(fp_line
			(start -0.67945 -0.3048)
			(end -0.67945 0.3048)
			(stroke
				(width 0.1)
				(type default)
			)
			(layer "B.Fab")
		)
		(fp_line
			(start -0.12065 -0.3048)
			(end -0.67945 -0.3048)
			(stroke
				(width 0.1)
				(type default)
			)
			(layer "B.Fab")
		)
		(fp_line
			(start 0.12065 -0.305054)
			(end 0.12065 -0.2794)
			(stroke
				(width 0.1)
				(type default)
			)
			(layer "B.Fab")
		)
		(fp_line
			(start 0.67945 -0.305054)
			(end 0.12065 -0.305054)
			(stroke
				(width 0.1)
				(type default)
			)
			(layer "B.Fab")
		)
		(pad "1" smd circle
			(at 0.40005 0 90)
			(size 0 0)
			(layers "B.Cu" "B.Mask" "B.Paste")
			(net "P3V3_AUX")
		)
		(pad "2" smd circle
			(at -0.40005 0 90)
			(size 0 0)
			(layers "B.Cu" "B.Mask" "B.Paste")
			(net "GND")
		)
	)
	(footprint ""
		(layer "B.Cu")
		(at 163.874958 -294.2082 -90)
		(property "Reference" "C3221"
			(at 0 0 90)
			(layer "B.SilkS")
			(hide yes)
			(effects
				(font
					(size 1.27 1.27)
				)
				(justify mirror)
			)
		)
		(property "Value" ""
			(at 0 0 90)
			(layer "B.Fab")
			(effects
				(font
					(size 1.27 1.27)
				)
				(justify mirror)
			)
		)
		(duplicate_pad_numbers_are_jumpers no)
		(fp_line
			(start -0.299974 0.150114)
			(end 0.299974 0.150114)
			(stroke
				(width 0.1)
				(type default)
			)
			(layer "B.Fab")
		)
		(fp_line
			(start 0.299974 0.150114)
			(end 0.299974 -0.150114)
			(stroke
				(width 0.1)
				(type default)
			)
			(layer "B.Fab")
		)
		(fp_line
			(start -0.299974 -0.150114)
			(end -0.299974 0.150114)
			(stroke
				(width 0.1)
				(type default)
			)
			(layer "B.Fab")
		)
		(fp_line
			(start 0.299974 -0.150114)
			(end -0.299974 -0.150114)
			(stroke
				(width 0.1)
				(type default)
			)
			(layer "B.Fab")
		)
		(pad "1" smd rect
			(at 0.2667 0 90)
			(size 0.3048 0.381)
			(layers "B.Cu" "B.Mask" "B.Paste")
			(net "PCEPLL5_VDDA18_PEX1")
		)
		(pad "2" smd rect
			(at -0.2667 0 90)
			(size 0.3048 0.381)
			(layers "B.Cu" "B.Mask" "B.Paste")
			(net "GND")
		)
	)
)
